(kicad_pcb
	(version 20260206)
	(generator "pcbnew")
	(generator_version "10.0")
	(general
		(thickness 1.6)
		(legacy_teardrops no)
	)
	(paper "A4")
	(title_block
		(title "04192023_DAF0TMB3IC0_F0TG_MB_C_brd_V02_OCP.brd")
		(comment 1 "Grand Teton / footprint 4188 of 8354 (J28), pads 114-226 of 291")
	)
	(layers
		(0 "F.Cu" signal "TOP")
		(4 "In1.Cu" signal "GND")
		(6 "In2.Cu" signal "IN1")
		(8 "In3.Cu" signal "GND1")
		(10 "In4.Cu" signal "IN2")
		(12 "In5.Cu" signal "GND2")
		(14 "In6.Cu" signal "IN3")
		(16 "In7.Cu" signal "GND3")
		(18 "In8.Cu" signal "VCC")
		(20 "In9.Cu" signal "VCC1")
		(22 "In10.Cu" signal "GND4")
		(24 "In11.Cu" signal "IN4")
		(26 "In12.Cu" signal "GND5")
		(28 "In13.Cu" signal "IN5")
		(30 "In14.Cu" signal "GND6")
		(32 "In15.Cu" signal "IN6")
		(34 "In16.Cu" signal "GND7")
		(2 "B.Cu" signal "BOTTOM")
		(9 "F.Adhes" user "F.Adhesive")
		(11 "B.Adhes" user "B.Adhesive")
		(13 "F.Paste" user "Package Geometry/Pastemask Top")
		(15 "B.Paste" user "Package Geometry/Pastemask Bottom")
		(5 "F.SilkS" user "Ref Des/Silkscreen Top")
		(7 "B.SilkS" user "Ref Des/Silkscreen Bottom")
		(1 "F.Mask" user "Board Geometry/Soldermask Top")
		(3 "B.Mask" user "Board Geometry/Soldermask Bottom")
		(17 "Dwgs.User" user "User.Drawings")
		(19 "Cmts.User" user "User.Comments")
		(21 "Eco1.User" user "User.Eco1")
		(23 "Eco2.User" user "User.Eco2")
		(25 "Edge.Cuts" user "Board Geometry/Outline")
		(27 "Margin" user)
		(31 "F.CrtYd" user "Package Geometry/Place Bound Top")
		(29 "B.CrtYd" user "Package Geometry/Place Bound Bottom")
		(35 "F.Fab" user "Ref Des/Assembly Top")
		(33 "B.Fab" user "Ref Des/Assembly Bottom")
	)
	(footprint ""
		(layer "F.Cu")
		(at 42.289984 -255.560322 180)
		(property "Reference" "J28"
			(at -2.876296 -82.230976 0)
			(unlocked yes)
			(layer "F.SilkS")
			(effects
				(font
					(size 0.7874 0.5842)
					(thickness 0.1524)
				)
			)
		)
		(property "Value" ""
			(at 0 0 180)
			(layer "F.Fab")
			(effects
				(font
					(size 1.27 1.27)
				)
			)
		)
		(duplicate_pad_numbers_are_jumpers no)
		(pad "114" smd rect
			(at -2.050034 37.824918 90)
			(size 0.519938 1.4986)
			(layers "F.Cu" "F.Mask" "F.Paste")
			(net "GND")
		)
		(pad "115" smd rect
			(at -2.050034 38.675056 90)
			(size 0.519938 1.4986)
			(layers "F.Cu" "F.Mask" "F.Paste")
			(net "M_C_CPU1_SB_DQS_DP<1>")
		)
		(pad "116" smd rect
			(at -2.050034 39.52494 90)
			(size 0.519938 1.4986)
			(layers "F.Cu" "F.Mask" "F.Paste")
			(net "M_C_CPU1_SB_DQS_DN<1>")
		)
		(pad "117" smd rect
			(at -2.050034 40.375078 90)
			(size 0.519938 1.4986)
			(layers "F.Cu" "F.Mask" "F.Paste")
			(net "GND")
		)
		(pad "118" smd rect
			(at -2.050034 41.224962 90)
			(size 0.519938 1.4986)
			(layers "F.Cu" "F.Mask" "F.Paste")
			(net "M_C_CPU1_SB_DQ<12>")
		)
		(pad "119" smd rect
			(at -2.050034 42.0751 90)
			(size 0.519938 1.4986)
			(layers "F.Cu" "F.Mask" "F.Paste")
			(net "GND")
		)
		(pad "120" smd rect
			(at -2.050034 42.924984 90)
			(size 0.519938 1.4986)
			(layers "F.Cu" "F.Mask" "F.Paste")
			(net "M_C_CPU1_SB_DQ<13>")
		)
		(pad "121" smd rect
			(at -2.050034 43.775122 90)
			(size 0.519938 1.4986)
			(layers "F.Cu" "F.Mask" "F.Paste")
			(net "GND")
		)
		(pad "122" smd rect
			(at -2.050034 44.625006 90)
			(size 0.519938 1.4986)
			(layers "F.Cu" "F.Mask" "F.Paste")
			(net "M_C_CPU1_SB_DQ<16>")
		)
		(pad "123" smd rect
			(at -2.050034 45.47489 90)
			(size 0.519938 1.4986)
			(layers "F.Cu" "F.Mask" "F.Paste")
			(net "GND")
		)
		(pad "124" smd rect
			(at -2.050034 46.325028 90)
			(size 0.519938 1.4986)
			(layers "F.Cu" "F.Mask" "F.Paste")
			(net "M_C_CPU1_SB_DQ<17>")
		)
		(pad "125" smd rect
			(at -2.050034 47.174912 90)
			(size 0.519938 1.4986)
			(layers "F.Cu" "F.Mask" "F.Paste")
			(net "GND")
		)
		(pad "126" smd rect
			(at -2.050034 48.02505 90)
			(size 0.519938 1.4986)
			(layers "F.Cu" "F.Mask" "F.Paste")
			(net "M_C_CPU1_SB_DQS_DP<2>")
		)
		(pad "127" smd rect
			(at -2.050034 48.874934 90)
			(size 0.519938 1.4986)
			(layers "F.Cu" "F.Mask" "F.Paste")
			(net "M_C_CPU1_SB_DQS_DN<2>")
		)
		(pad "128" smd rect
			(at -2.050034 49.725072 90)
			(size 0.519938 1.4986)
			(layers "F.Cu" "F.Mask" "F.Paste")
			(net "GND")
		)
		(pad "129" smd rect
			(at -2.050034 50.574956 90)
			(size 0.519938 1.4986)
			(layers "F.Cu" "F.Mask" "F.Paste")
			(net "M_C_CPU1_SB_DQ<20>")
		)
		(pad "130" smd rect
			(at -2.050034 51.425094 90)
			(size 0.519938 1.4986)
			(layers "F.Cu" "F.Mask" "F.Paste")
			(net "GND")
		)
		(pad "131" smd rect
			(at -2.050034 52.274978 90)
			(size 0.519938 1.4986)
			(layers "F.Cu" "F.Mask" "F.Paste")
			(net "M_C_CPU1_SB_DQ<21>")
		)
		(pad "132" smd rect
			(at -2.050034 53.125116 90)
			(size 0.519938 1.4986)
			(layers "F.Cu" "F.Mask" "F.Paste")
			(net "GND")
		)
		(pad "133" smd rect
			(at -2.050034 53.975 90)
			(size 0.519938 1.4986)
			(layers "F.Cu" "F.Mask" "F.Paste")
			(net "M_C_CPU1_SB_DQ<24>")
		)
		(pad "134" smd rect
			(at -2.050034 54.824884 90)
			(size 0.519938 1.4986)
			(layers "F.Cu" "F.Mask" "F.Paste")
			(net "GND")
		)
		(pad "135" smd rect
			(at -2.050034 55.675022 90)
			(size 0.519938 1.4986)
			(layers "F.Cu" "F.Mask" "F.Paste")
			(net "M_C_CPU1_SB_DQ<25>")
		)
		(pad "136" smd rect
			(at -2.050034 56.524906 90)
			(size 0.519938 1.4986)
			(layers "F.Cu" "F.Mask" "F.Paste")
			(net "GND")
		)
		(pad "137" smd rect
			(at -2.050034 57.375044 90)
			(size 0.519938 1.4986)
			(layers "F.Cu" "F.Mask" "F.Paste")
			(net "M_C_CPU1_SB_DQS_DP<3>")
		)
		(pad "138" smd rect
			(at -2.050034 58.224928 90)
			(size 0.519938 1.4986)
			(layers "F.Cu" "F.Mask" "F.Paste")
			(net "M_C_CPU1_SB_DQS_DN<3>")
		)
		(pad "139" smd rect
			(at -2.050034 59.075066 90)
			(size 0.519938 1.4986)
			(layers "F.Cu" "F.Mask" "F.Paste")
			(net "GND")
		)
		(pad "140" smd rect
			(at -2.050034 59.92495 90)
			(size 0.519938 1.4986)
			(layers "F.Cu" "F.Mask" "F.Paste")
			(net "M_C_CPU1_SB_DQ<28>")
		)
		(pad "141" smd rect
			(at -2.050034 60.775088 90)
			(size 0.519938 1.4986)
			(layers "F.Cu" "F.Mask" "F.Paste")
			(net "GND")
		)
		(pad "142" smd rect
			(at -2.050034 61.624972 90)
			(size 0.519938 1.4986)
			(layers "F.Cu" "F.Mask" "F.Paste")
			(net "M_C_CPU1_SB_DQ<29>")
		)
		(pad "143" smd rect
			(at -2.050034 62.47511 90)
			(size 0.519938 1.4986)
			(layers "F.Cu" "F.Mask" "F.Paste")
			(net "GND")
		)
		(pad "144" smd rect
			(at -2.050034 63.324994 90)
			(size 0.519938 1.4986)
			(layers "F.Cu" "F.Mask" "F.Paste")
			(net "Net_2285")
		)
		(pad "145" smd rect
			(at 2.050034 -63.324994 90)
			(size 0.519938 1.4986)
			(layers "F.Cu" "F.Mask" "F.Paste")
			(net "P12V_MEM_CPU1")
		)
		(pad "146" smd rect
			(at 2.050034 -62.47511 90)
			(size 0.519938 1.4986)
			(layers "F.Cu" "F.Mask" "F.Paste")
			(net "P12V_MEM_CPU1")
		)
		(pad "147" smd rect
			(at 2.050034 -61.624972 90)
			(size 0.519938 1.4986)
			(layers "F.Cu" "F.Mask" "F.Paste")
			(net "PWRGD_CHC_CPU1_DIMM")
		)
		(pad "148" smd rect
			(at 2.050034 -60.775088 90)
			(size 0.519938 1.4986)
			(layers "F.Cu" "F.Mask" "F.Paste")
			(net "PD_CHC_CPU1_DIMM_SAA")
		)
		(pad "149" smd rect
			(at 2.050034 -59.92495 90)
			(size 0.519938 1.4986)
			(layers "F.Cu" "F.Mask" "F.Paste")
			(net "Net_2286")
		)
		(pad "150" smd rect
			(at 2.050034 -59.075066 90)
			(size 0.519938 1.4986)
			(layers "F.Cu" "F.Mask" "F.Paste")
			(net "Net_2287")
		)
		(pad "151" smd rect
			(at 2.050034 -58.224928 90)
			(size 0.519938 1.4986)
			(layers "F.Cu" "F.Mask" "F.Paste")
			(net "GND")
		)
		(pad "152" smd rect
			(at 2.050034 -57.375044 90)
			(size 0.519938 1.4986)
			(layers "F.Cu" "F.Mask" "F.Paste")
			(net "M_C_CPU1_SA_DQ<2>")
		)
		(pad "153" smd rect
			(at 2.050034 -56.524906 90)
			(size 0.519938 1.4986)
			(layers "F.Cu" "F.Mask" "F.Paste")
			(net "GND")
		)
		(pad "154" smd rect
			(at 2.050034 -55.675022 90)
			(size 0.519938 1.4986)
			(layers "F.Cu" "F.Mask" "F.Paste")
			(net "M_C_CPU1_SA_DQ<3>")
		)
		(pad "155" smd rect
			(at 2.050034 -54.824884 90)
			(size 0.519938 1.4986)
			(layers "F.Cu" "F.Mask" "F.Paste")
			(net "GND")
		)
		(pad "156" smd rect
			(at 2.050034 -53.975 90)
			(size 0.519938 1.4986)
			(layers "F.Cu" "F.Mask" "F.Paste")
			(net "M_C_CPU1_SA_DQS_DN<5>")
		)
		(pad "157" smd rect
			(at 2.050034 -53.125116 90)
			(size 0.519938 1.4986)
			(layers "F.Cu" "F.Mask" "F.Paste")
			(net "M_C_CPU1_SA_DQS_DP<5>")
		)
		(pad "158" smd rect
			(at 2.050034 -52.274978 90)
			(size 0.519938 1.4986)
			(layers "F.Cu" "F.Mask" "F.Paste")
			(net "GND")
		)
		(pad "159" smd rect
			(at 2.050034 -51.425094 90)
			(size 0.519938 1.4986)
			(layers "F.Cu" "F.Mask" "F.Paste")
			(net "M_C_CPU1_SA_DQ<6>")
		)
		(pad "160" smd rect
			(at 2.050034 -50.574956 90)
			(size 0.519938 1.4986)
			(layers "F.Cu" "F.Mask" "F.Paste")
			(net "GND")
		)
		(pad "161" smd rect
			(at 2.050034 -49.725072 90)
			(size 0.519938 1.4986)
			(layers "F.Cu" "F.Mask" "F.Paste")
			(net "M_C_CPU1_SA_DQ<7>")
		)
		(pad "162" smd rect
			(at 2.050034 -48.874934 90)
			(size 0.519938 1.4986)
			(layers "F.Cu" "F.Mask" "F.Paste")
			(net "GND")
		)
		(pad "163" smd rect
			(at 2.050034 -48.02505 90)
			(size 0.519938 1.4986)
			(layers "F.Cu" "F.Mask" "F.Paste")
			(net "M_C_CPU1_SA_DQ<10>")
		)
		(pad "164" smd rect
			(at 2.050034 -47.174912 90)
			(size 0.519938 1.4986)
			(layers "F.Cu" "F.Mask" "F.Paste")
			(net "GND")
		)
		(pad "165" smd rect
			(at 2.050034 -46.325028 90)
			(size 0.519938 1.4986)
			(layers "F.Cu" "F.Mask" "F.Paste")
			(net "M_C_CPU1_SA_DQ<11>")
		)
		(pad "166" smd rect
			(at 2.050034 -45.47489 90)
			(size 0.519938 1.4986)
			(layers "F.Cu" "F.Mask" "F.Paste")
			(net "GND")
		)
		(pad "167" smd rect
			(at 2.050034 -44.625006 90)
			(size 0.519938 1.4986)
			(layers "F.Cu" "F.Mask" "F.Paste")
			(net "M_C_CPU1_SA_DQS_DN<6>")
		)
		(pad "168" smd rect
			(at 2.050034 -43.775122 90)
			(size 0.519938 1.4986)
			(layers "F.Cu" "F.Mask" "F.Paste")
			(net "M_C_CPU1_SA_DQS_DP<6>")
		)
		(pad "169" smd rect
			(at 2.050034 -42.924984 90)
			(size 0.519938 1.4986)
			(layers "F.Cu" "F.Mask" "F.Paste")
			(net "GND")
		)
		(pad "170" smd rect
			(at 2.050034 -42.0751 90)
			(size 0.519938 1.4986)
			(layers "F.Cu" "F.Mask" "F.Paste")
			(net "M_C_CPU1_SA_DQ<14>")
		)
		(pad "171" smd rect
			(at 2.050034 -41.224962 90)
			(size 0.519938 1.4986)
			(layers "F.Cu" "F.Mask" "F.Paste")
			(net "GND")
		)
		(pad "172" smd rect
			(at 2.050034 -40.375078 90)
			(size 0.519938 1.4986)
			(layers "F.Cu" "F.Mask" "F.Paste")
			(net "M_C_CPU1_SA_DQ<15>")
		)
		(pad "173" smd rect
			(at 2.050034 -39.52494 90)
			(size 0.519938 1.4986)
			(layers "F.Cu" "F.Mask" "F.Paste")
			(net "GND")
		)
		(pad "174" smd rect
			(at 2.050034 -38.675056 90)
			(size 0.519938 1.4986)
			(layers "F.Cu" "F.Mask" "F.Paste")
			(net "M_C_CPU1_SA_DQ<18>")
		)
		(pad "175" smd rect
			(at 2.050034 -37.824918 90)
			(size 0.519938 1.4986)
			(layers "F.Cu" "F.Mask" "F.Paste")
			(net "GND")
		)
		(pad "176" smd rect
			(at 2.050034 -36.975034 90)
			(size 0.519938 1.4986)
			(layers "F.Cu" "F.Mask" "F.Paste")
			(net "M_C_CPU1_SA_DQ<19>")
		)
		(pad "177" smd rect
			(at 2.050034 -36.124896 90)
			(size 0.519938 1.4986)
			(layers "F.Cu" "F.Mask" "F.Paste")
			(net "GND")
		)
		(pad "178" smd rect
			(at 2.050034 -35.275012 90)
			(size 0.519938 1.4986)
			(layers "F.Cu" "F.Mask" "F.Paste")
			(net "M_C_CPU1_SA_DQS_DN<7>")
		)
		(pad "179" smd rect
			(at 2.050034 -34.425128 90)
			(size 0.519938 1.4986)
			(layers "F.Cu" "F.Mask" "F.Paste")
			(net "M_C_CPU1_SA_DQS_DP<7>")
		)
		(pad "180" smd rect
			(at 2.050034 -33.57499 90)
			(size 0.519938 1.4986)
			(layers "F.Cu" "F.Mask" "F.Paste")
			(net "GND")
		)
		(pad "181" smd rect
			(at 2.050034 -32.725106 90)
			(size 0.519938 1.4986)
			(layers "F.Cu" "F.Mask" "F.Paste")
			(net "M_C_CPU1_SA_DQ<22>")
		)
		(pad "182" smd rect
			(at 2.050034 -31.874968 90)
			(size 0.519938 1.4986)
			(layers "F.Cu" "F.Mask" "F.Paste")
			(net "GND")
		)
		(pad "183" smd rect
			(at 2.050034 -31.025084 90)
			(size 0.519938 1.4986)
			(layers "F.Cu" "F.Mask" "F.Paste")
			(net "M_C_CPU1_SA_DQ<23>")
		)
		(pad "184" smd rect
			(at 2.050034 -30.174946 90)
			(size 0.519938 1.4986)
			(layers "F.Cu" "F.Mask" "F.Paste")
			(net "GND")
		)
		(pad "185" smd rect
			(at 2.050034 -29.325062 90)
			(size 0.519938 1.4986)
			(layers "F.Cu" "F.Mask" "F.Paste")
			(net "M_C_CPU1_SA_DQ<26>")
		)
		(pad "186" smd rect
			(at 2.050034 -28.474924 90)
			(size 0.519938 1.4986)
			(layers "F.Cu" "F.Mask" "F.Paste")
			(net "GND")
		)
		(pad "187" smd rect
			(at 2.050034 -27.62504 90)
			(size 0.519938 1.4986)
			(layers "F.Cu" "F.Mask" "F.Paste")
			(net "M_C_CPU1_SA_DQ<27>")
		)
		(pad "188" smd rect
			(at 2.050034 -26.774902 90)
			(size 0.519938 1.4986)
			(layers "F.Cu" "F.Mask" "F.Paste")
			(net "GND")
		)
		(pad "189" smd rect
			(at 2.050034 -25.925018 90)
			(size 0.519938 1.4986)
			(layers "F.Cu" "F.Mask" "F.Paste")
			(net "M_C_CPU1_SA_DQS_DN<8>")
		)
		(pad "190" smd rect
			(at 2.050034 -25.07488 90)
			(size 0.519938 1.4986)
			(layers "F.Cu" "F.Mask" "F.Paste")
			(net "M_C_CPU1_SA_DQS_DP<8>")
		)
		(pad "191" smd rect
			(at 2.050034 -24.224996 90)
			(size 0.519938 1.4986)
			(layers "F.Cu" "F.Mask" "F.Paste")
			(net "GND")
		)
		(pad "192" smd rect
			(at 2.050034 -23.375112 90)
			(size 0.519938 1.4986)
			(layers "F.Cu" "F.Mask" "F.Paste")
			(net "M_C_CPU1_SA_DQ<30>")
		)
		(pad "193" smd rect
			(at 2.050034 -22.524974 90)
			(size 0.519938 1.4986)
			(layers "F.Cu" "F.Mask" "F.Paste")
			(net "GND")
		)
		(pad "194" smd rect
			(at 2.050034 -21.67509 90)
			(size 0.519938 1.4986)
			(layers "F.Cu" "F.Mask" "F.Paste")
			(net "M_C_CPU1_SA_DQ<31>")
		)
		(pad "195" smd rect
			(at 2.050034 -20.824952 90)
			(size 0.519938 1.4986)
			(layers "F.Cu" "F.Mask" "F.Paste")
			(net "GND")
		)
		(pad "196" smd rect
			(at 2.050034 -19.975068 90)
			(size 0.519938 1.4986)
			(layers "F.Cu" "F.Mask" "F.Paste")
			(net "M_C_CPU1_SA_CB<2>")
		)
		(pad "197" smd rect
			(at 2.050034 -19.12493 90)
			(size 0.519938 1.4986)
			(layers "F.Cu" "F.Mask" "F.Paste")
			(net "GND")
		)
		(pad "198" smd rect
			(at 2.050034 -18.275046 90)
			(size 0.519938 1.4986)
			(layers "F.Cu" "F.Mask" "F.Paste")
			(net "M_C_CPU1_SA_CB<3>")
		)
		(pad "199" smd rect
			(at 2.050034 -17.424908 90)
			(size 0.519938 1.4986)
			(layers "F.Cu" "F.Mask" "F.Paste")
			(net "GND")
		)
		(pad "200" smd rect
			(at 2.050034 -16.575024 90)
			(size 0.519938 1.4986)
			(layers "F.Cu" "F.Mask" "F.Paste")
			(net "M_C_CPU1_SA_DQS_DN<9>")
		)
		(pad "201" smd rect
			(at 2.050034 -15.724886 90)
			(size 0.519938 1.4986)
			(layers "F.Cu" "F.Mask" "F.Paste")
			(net "M_C_CPU1_SA_DQS_DP<9>")
		)
		(pad "202" smd rect
			(at 2.050034 -14.875002 90)
			(size 0.519938 1.4986)
			(layers "F.Cu" "F.Mask" "F.Paste")
			(net "GND")
		)
		(pad "203" smd rect
			(at 2.050034 -14.025118 90)
			(size 0.519938 1.4986)
			(layers "F.Cu" "F.Mask" "F.Paste")
			(net "M_C_CPU1_SA_CB<6>")
		)
		(pad "204" smd rect
			(at 2.050034 -13.17498 90)
			(size 0.519938 1.4986)
			(layers "F.Cu" "F.Mask" "F.Paste")
			(net "GND")
		)
		(pad "205" smd rect
			(at 2.050034 -12.325096 90)
			(size 0.519938 1.4986)
			(layers "F.Cu" "F.Mask" "F.Paste")
			(net "M_C_CPU1_SA_CB<7>")
		)
		(pad "206" smd rect
			(at 2.050034 -11.474958 90)
			(size 0.519938 1.4986)
			(layers "F.Cu" "F.Mask" "F.Paste")
			(net "GND")
		)
		(pad "207" smd rect
			(at 2.050034 -10.625074 90)
			(size 0.519938 1.4986)
			(layers "F.Cu" "F.Mask" "F.Paste")
			(net "M_C_CPU1_RESET_N")
		)
		(pad "208" smd rect
			(at 2.050034 -9.774936 90)
			(size 0.519938 1.4986)
			(layers "F.Cu" "F.Mask" "F.Paste")
			(net "GND")
		)
		(pad "209" smd rect
			(at 2.050034 -8.925052 90)
			(size 0.519938 1.4986)
			(layers "F.Cu" "F.Mask" "F.Paste")
			(net "M_C_CPU1_SA_CS_N<1>")
		)
		(pad "210" smd rect
			(at 2.050034 -8.074914 90)
			(size 0.519938 1.4986)
			(layers "F.Cu" "F.Mask" "F.Paste")
			(net "GND")
		)
		(pad "211" smd rect
			(at 2.050034 -7.22503 90)
			(size 0.519938 1.4986)
			(layers "F.Cu" "F.Mask" "F.Paste")
			(net "M_C_CPU1_SA_CA<1>")
		)
		(pad "212" smd rect
			(at 2.050034 -6.374892 90)
			(size 0.519938 1.4986)
			(layers "F.Cu" "F.Mask" "F.Paste")
			(net "GND")
		)
		(pad "213" smd rect
			(at 2.050034 -5.525008 90)
			(size 0.519938 1.4986)
			(layers "F.Cu" "F.Mask" "F.Paste")
			(net "M_C_CPU1_SA_CA<3>")
		)
		(pad "214" smd rect
			(at 2.050034 -4.675124 90)
			(size 0.519938 1.4986)
			(layers "F.Cu" "F.Mask" "F.Paste")
			(net "GND")
		)
		(pad "215" smd rect
			(at 2.050034 -3.824986 90)
			(size 0.519938 1.4986)
			(layers "F.Cu" "F.Mask" "F.Paste")
			(net "M_C_CPU1_SA_CA<5>")
		)
		(pad "216" smd rect
			(at 2.050034 -2.975102 90)
			(size 0.519938 1.4986)
			(layers "F.Cu" "F.Mask" "F.Paste")
			(net "GND")
		)
		(pad "217" smd rect
			(at 2.050034 -2.124964 90)
			(size 0.519938 1.4986)
			(layers "F.Cu" "F.Mask" "F.Paste")
			(net "M_C_CPU1_CLK_DP<0>")
		)
		(pad "218" smd rect
			(at 2.050034 -1.27508 90)
			(size 0.519938 1.4986)
			(layers "F.Cu" "F.Mask" "F.Paste")
			(net "M_C_CPU1_CLK_DN<0>")
		)
		(pad "219" smd rect
			(at 2.050034 -0.424942 90)
			(size 0.519938 1.4986)
			(layers "F.Cu" "F.Mask" "F.Paste")
			(net "GND")
		)
		(pad "220" smd rect
			(at 2.050034 5.525008 90)
			(size 0.519938 1.4986)
			(layers "F.Cu" "F.Mask" "F.Paste")
			(net "Net_2288")
		)
		(pad "221" smd rect
			(at 2.050034 6.374892 90)
			(size 0.519938 1.4986)
			(layers "F.Cu" "F.Mask" "F.Paste")
			(net "M_C_CPU1_SB_CA<1>")
		)
		(pad "222" smd rect
			(at 2.050034 7.22503 90)
			(size 0.519938 1.4986)
			(layers "F.Cu" "F.Mask" "F.Paste")
			(net "GND")
		)
		(pad "223" smd rect
			(at 2.050034 8.074914 90)
			(size 0.519938 1.4986)
			(layers "F.Cu" "F.Mask" "F.Paste")
			(net "M_C_CPU1_SB_CA<3>")
		)
		(pad "224" smd rect
			(at 2.050034 8.925052 90)
			(size 0.519938 1.4986)
			(layers "F.Cu" "F.Mask" "F.Paste")
			(net "GND")
		)
		(pad "225" smd rect
			(at 2.050034 9.774936 90)
			(size 0.519938 1.4986)
			(layers "F.Cu" "F.Mask" "F.Paste")
			(net "M_C_CPU1_SB_CA<5>")
		)
		(pad "226" smd rect
			(at 2.050034 10.625074 90)
			(size 0.519938 1.4986)
			(layers "F.Cu" "F.Mask" "F.Paste")
			(net "GND")
		)
	)
)
